(kicad_pcb
	(version 20260206)
	(generator "pcbnew")
	(generator_version "10.0")
	(general
		(thickness 1.6)
		(legacy_teardrops no)
	)
	(paper "A4")
	(title_block
		(title "Bryce Canyon_R.DPB_16317-1_OCP.brd")
		(comment 1 "Bryce Canyon / footprints 1329-1336 of 2099")
	)
	(layers
		(0 "F.Cu" signal "TOP")
		(4 "In1.Cu" signal "L2GND")
		(6 "In2.Cu" signal "L3")
		(8 "In3.Cu" signal "L4VCC")
		(10 "In4.Cu" signal "L5VCC")
		(12 "In5.Cu" signal "L6")
		(14 "In6.Cu" signal "L7GND")
		(2 "B.Cu" signal "BOTTOM")
		(9 "F.Adhes" user "F.Adhesive")
		(11 "B.Adhes" user "B.Adhesive")
		(13 "F.Paste" user "Package Geometry/Pastemask Top")
		(15 "B.Paste" user "Package Geometry/Pastemask Bottom")
		(5 "F.SilkS" user "Ref Des/Silkscreen Top")
		(7 "B.SilkS" user "Ref Des/Silkscreen Bottom")
		(1 "F.Mask" user "Board Geometry/Soldermask Top")
		(3 "B.Mask" user "Board Geometry/Soldermask Bottom")
		(17 "Dwgs.User" user "User.Drawings")
		(19 "Cmts.User" user "User.Comments")
		(21 "Eco1.User" user "User.Eco1")
		(23 "Eco2.User" user "User.Eco2")
		(25 "Edge.Cuts" user "Board Geometry/Outline")
		(27 "Margin" user)
		(31 "F.CrtYd" user "Package Geometry/Place Bound Top")
		(29 "B.CrtYd" user "Package Geometry/Place Bound Bottom")
		(35 "F.Fab" user "Ref Des/Assembly Top")
		(33 "B.Fab" user "Ref Des/Assembly Bottom")
	)
	(footprint ""
		(layer "F.Cu")
		(at 221.375224 -329.060556)
		(property "Reference" "C509"
			(at 0 0 0)
			(layer "F.SilkS")
			(hide yes)
			(effects
				(font
					(size 1.27 1.27)
				)
			)
		)
		(property "Value" "SC22U25V6KX-2-GP-U"
			(at -2.860802 -5.279644 0)
			(unlocked yes)
			(layer "F.Fab")
			(hide yes)
			(effects
				(font
					(size 1.016 1.016)
					(thickness 0.1524)
				)
			)
		)
		(property "Device Type" "C1206-TO0D3H75"
			(at -2.860802 -6.803644 0)
			(unlocked yes)
			(layer "F.Fab")
			(hide yes)
			(effects
				(font
					(size 1.016 1.016)
					(thickness 0.1524)
				)
			)
		)
		(duplicate_pad_numbers_are_jumpers no)
		(fp_line
			(start -1.3081 -2.3749)
			(end 1.3081 -2.3749)
			(stroke
				(width 0.1524)
				(type default)
			)
			(layer "F.SilkS")
		)
		(fp_line
			(start -1.3081 2.3749)
			(end -1.3081 -2.3749)
			(stroke
				(width 0.1524)
				(type default)
			)
			(layer "F.SilkS")
		)
		(fp_line
			(start 1.3081 -2.3749)
			(end 1.3081 2.3749)
			(stroke
				(width 0.1524)
				(type default)
			)
			(layer "F.SilkS")
		)
		(fp_line
			(start 1.3081 2.3749)
			(end -1.3081 2.3749)
			(stroke
				(width 0.1524)
				(type default)
			)
			(layer "F.SilkS")
		)
		(fp_rect
			(start -0.8001 1.6002)
			(end 0.8001 -1.6002)
			(stroke
				(width 0)
				(type default)
			)
			(fill no)
			(layer "F.CrtYd")
		)
		(fp_poly
			(pts
				(xy -1.5621 2.4511) (xy -1.5621 1.6002) (xy 0.8001 1.6002) (xy 0.8001 -1.6002) (xy -0.8001 -1.6002)
				(xy -0.8001 1.5875) (xy -1.5621 1.5875) (xy -1.5621 -2.4511) (xy 1.5621 -2.4511) (xy 1.5621 2.4511)
			)
			(stroke
				(width 0)
				(type default)
			)
			(fill no)
			(layer "F.CrtYd")
		)
		(fp_rect
			(start -1.5621 2.4511)
			(end 1.5621 -2.4511)
			(stroke
				(width 0)
				(type default)
			)
			(fill no)
			(layer "F.Fab")
		)
		(pad "1" smd rect
			(at 0 -1.392936)
			(size 2.1082 1.4478)
			(layers "F.Cu" "F.Mask" "F.Paste")
			(net "P12V_IN")
		)
		(pad "2" smd rect
			(at 0 1.392936)
			(size 2.1082 1.4478)
			(layers "F.Cu" "F.Mask" "F.Paste")
			(net "GND")
		)
	)
	(footprint ""
		(layer "F.Cu")
		(at 190.213488 -15.219426 90)
		(property "Reference" "C405"
			(at 0 0 90)
			(layer "F.SilkS")
			(hide yes)
			(effects
				(font
					(size 1.27 1.27)
				)
			)
		)
		(property "Value" "SCD01U16V1KX-GP"
			(at -2.8321 -1.7399 90)
			(unlocked yes)
			(layer "F.Fab")
			(hide yes)
			(effects
				(font
					(size 1.016 1.016)
					(thickness 0.1524)
				)
			)
		)
		(property "Device Type" "C0201H13"
			(at -2.8321 -3.2639 90)
			(unlocked yes)
			(layer "F.Fab")
			(hide yes)
			(effects
				(font
					(size 1.016 1.016)
					(thickness 0.1524)
				)
			)
		)
		(duplicate_pad_numbers_are_jumpers no)
		(fp_rect
			(start -0.2794 0.6477)
			(end 0.2794 -0.6477)
			(stroke
				(width 0)
				(type default)
			)
			(fill no)
			(layer "F.CrtYd")
		)
		(fp_rect
			(start -0.2794 0.6477)
			(end 0.2794 -0.6477)
			(stroke
				(width 0)
				(type default)
			)
			(fill no)
			(layer "F.Fab")
		)
		(pad "1" smd custom
			(at 0 -0.2794 90)
			(size 0.0762 0.0762)
			(layers "F.Cu" "F.Mask" "F.Paste")
			(net "SAS_HDD_RX_N29")
			(options
				(clearance outline)
				(anchor circle)
			)
			(primitives
				(gr_poly
					(pts
						(arc
							(start 0.1524 -0.127)
							(mid 0.137521 -0.162921)
							(end 0.1016 -0.1778)
						)
						(arc
							(start -0.1016 -0.1778)
							(mid -0.137521 -0.162921)
							(end -0.1524 -0.127)
						)
						(arc
							(start -0.1524 0.127)
							(mid -0.137521 0.162921)
							(end -0.1016 0.1778)
						)
						(arc
							(start 0.1016 0.1778)
							(mid 0.137521 0.162921)
							(end 0.1524 0.127)
						)
					)
					(width 0)
					(fill yes)
				)
			)
		)
		(pad "2" smd custom
			(at 0 0.2794 90)
			(size 0.0762 0.0762)
			(layers "F.Cu" "F.Mask" "F.Paste")
			(net "PHY_SCC_B_TO_DRV_B_29_DN")
			(options
				(clearance outline)
				(anchor circle)
			)
			(primitives
				(gr_poly
					(pts
						(arc
							(start 0.1524 -0.127)
							(mid 0.137521 -0.162921)
							(end 0.1016 -0.1778)
						)
						(arc
							(start -0.1016 -0.1778)
							(mid -0.137521 -0.162921)
							(end -0.1524 -0.127)
						)
						(arc
							(start -0.1524 0.127)
							(mid -0.137521 0.162921)
							(end -0.1016 0.1778)
						)
						(arc
							(start 0.1016 0.1778)
							(mid 0.137521 0.162921)
							(end 0.1524 0.127)
						)
					)
					(width 0)
					(fill yes)
				)
			)
		)
	)
	(footprint ""
		(layer "F.Cu")
		(at 285.016448 -347.541342 180)
		(property "Reference" "R1071"
			(at 0 0 180)
			(layer "F.SilkS")
			(hide yes)
			(effects
				(font
					(size 1.27 1.27)
				)
			)
		)
		(property "Value" "4K7R2F-GP"
			(at 0.064008 -3.993896 180)
			(unlocked yes)
			(layer "F.Fab")
			(hide yes)
			(effects
				(font
					(size 1.016 1.016)
					(thickness 0.1524)
				)
			)
		)
		(property "Device Type" "R402H16"
			(at 0.064008 -5.517896 180)
			(unlocked yes)
			(layer "F.Fab")
			(hide yes)
			(effects
				(font
					(size 1.016 1.016)
					(thickness 0.1524)
				)
			)
		)
		(duplicate_pad_numbers_are_jumpers no)
		(fp_line
			(start 0.508 -0.9398)
			(end -0.508 -0.9398)
			(stroke
				(width 0.1524)
				(type default)
			)
			(layer "F.SilkS")
		)
		(fp_line
			(start -0.508 -0.9398)
			(end -0.508 0.9398)
			(stroke
				(width 0.1524)
				(type default)
			)
			(layer "F.SilkS")
		)
		(fp_rect
			(start -0.508 0.9398)
			(end 0.508 -0.9398)
			(stroke
				(width 0)
				(type default)
			)
			(fill no)
			(layer "F.CrtYd")
		)
		(fp_rect
			(start -0.508 0.9398)
			(end 0.508 -0.9398)
			(stroke
				(width 0)
				(type default)
			)
			(fill no)
			(layer "F.Fab")
		)
		(pad "1" smd custom
			(at 0 -0.4445 180)
			(size 0.1397 0.1397)
			(layers "F.Cu" "F.Mask" "F.Paste")
			(net "P3V3_STBY_B")
			(options
				(clearance outline)
				(anchor circle)
			)
			(primitives
				(gr_poly
					(pts
						(arc
							(start -0.1778 -0.2794)
							(mid -0.249642 -0.249642)
							(end -0.2794 -0.1778)
						)
						(arc
							(start -0.2794 0.1778)
							(mid -0.249642 0.249642)
							(end -0.1778 0.2794)
						)
						(arc
							(start 0.1778 0.2794)
							(mid 0.249642 0.249642)
							(end 0.2794 0.1778)
						)
						(arc
							(start 0.2794 -0.1778)
							(mid 0.249642 -0.249642)
							(end 0.1778 -0.2794)
						)
					)
					(width 0)
					(fill yes)
				)
			)
		)
		(pad "2" smd custom
			(at 0 0.4445 180)
			(size 0.1397 0.1397)
			(layers "F.Cu" "F.Mask" "F.Paste")
			(net "MAX31790_B_ADD1")
			(options
				(clearance outline)
				(anchor circle)
			)
			(primitives
				(gr_poly
					(pts
						(arc
							(start -0.1778 -0.2794)
							(mid -0.249642 -0.249642)
							(end -0.2794 -0.1778)
						)
						(arc
							(start -0.2794 0.1778)
							(mid -0.249642 0.249642)
							(end -0.1778 0.2794)
						)
						(arc
							(start 0.1778 0.2794)
							(mid 0.249642 0.249642)
							(end 0.2794 0.1778)
						)
						(arc
							(start 0.2794 -0.1778)
							(mid 0.249642 -0.249642)
							(end 0.1778 -0.2794)
						)
					)
					(width 0)
					(fill yes)
				)
			)
		)
	)
	(footprint ""
		(layer "F.Cu")
		(at 466.451696 -212.390228 -90)
		(property "Reference" "R325"
			(at 0 0 270)
			(layer "F.SilkS")
			(hide yes)
			(effects
				(font
					(size 1.27 1.27)
				)
			)
		)
		(property "Value" "4K7R2F-GP"
			(at 0.064008 -3.993896 270)
			(unlocked yes)
			(layer "F.Fab")
			(hide yes)
			(effects
				(font
					(size 1.016 1.016)
					(thickness 0.1524)
				)
			)
		)
		(property "Device Type" "R402H16"
			(at 0.064008 -5.517896 270)
			(unlocked yes)
			(layer "F.Fab")
			(hide yes)
			(effects
				(font
					(size 1.016 1.016)
					(thickness 0.1524)
				)
			)
		)
		(duplicate_pad_numbers_are_jumpers no)
		(fp_line
			(start -0.508 -0.9398)
			(end -0.508 0.9398)
			(stroke
				(width 0.1524)
				(type default)
			)
			(layer "F.SilkS")
		)
		(fp_line
			(start 0.508 -0.9398)
			(end -0.508 -0.9398)
			(stroke
				(width 0.1524)
				(type default)
			)
			(layer "F.SilkS")
		)
		(fp_rect
			(start -0.508 0.9398)
			(end 0.508 -0.9398)
			(stroke
				(width 0)
				(type default)
			)
			(fill no)
			(layer "F.CrtYd")
		)
		(fp_rect
			(start -0.508 0.9398)
			(end 0.508 -0.9398)
			(stroke
				(width 0)
				(type default)
			)
			(fill no)
			(layer "F.Fab")
		)
		(pad "1" smd custom
			(at 0 -0.4445 270)
			(size 0.1397 0.1397)
			(layers "F.Cu" "F.Mask" "F.Paste")
			(net "DRIVE_B_11_ACT")
			(options
				(clearance outline)
				(anchor circle)
			)
			(primitives
				(gr_poly
					(pts
						(arc
							(start -0.1778 -0.2794)
							(mid -0.249642 -0.249642)
							(end -0.2794 -0.1778)
						)
						(arc
							(start -0.2794 0.1778)
							(mid -0.249642 0.249642)
							(end -0.1778 0.2794)
						)
						(arc
							(start 0.1778 0.2794)
							(mid 0.249642 0.249642)
							(end 0.2794 0.1778)
						)
						(arc
							(start 0.2794 -0.1778)
							(mid 0.249642 -0.249642)
							(end 0.1778 -0.2794)
						)
					)
					(width 0)
					(fill yes)
				)
			)
		)
		(pad "2" smd custom
			(at 0 0.4445 270)
			(size 0.1397 0.1397)
			(layers "F.Cu" "F.Mask" "F.Paste")
			(net "GND")
			(options
				(clearance outline)
				(anchor circle)
			)
			(primitives
				(gr_poly
					(pts
						(arc
							(start -0.1778 -0.2794)
							(mid -0.249642 -0.249642)
							(end -0.2794 -0.1778)
						)
						(arc
							(start -0.2794 0.1778)
							(mid -0.249642 0.249642)
							(end -0.1778 0.2794)
						)
						(arc
							(start 0.1778 0.2794)
							(mid 0.249642 0.249642)
							(end 0.2794 0.1778)
						)
						(arc
							(start 0.2794 -0.1778)
							(mid 0.249642 -0.249642)
							(end 0.1778 -0.2794)
						)
					)
					(width 0)
					(fill yes)
				)
			)
		)
	)
	(footprint ""
		(layer "F.Cu")
		(at 77.978 -140.462 90)
		(property "Reference" "C221"
			(at 0 0 90)
			(layer "F.SilkS")
			(hide yes)
			(effects
				(font
					(size 1.27 1.27)
				)
			)
		)
		(property "Value" "SCD033U25V2KX-GP"
			(at 1.1811 -2.7051 90)
			(unlocked yes)
			(layer "F.Fab")
			(hide yes)
			(effects
				(font
					(size 1.016 1.016)
					(thickness 0.1524)
				)
			)
		)
		(property "Device Type" "C402H22"
			(at 1.1811 -4.2291 90)
			(unlocked yes)
			(layer "F.Fab")
			(hide yes)
			(effects
				(font
					(size 1.016 1.016)
					(thickness 0.1524)
				)
			)
		)
		(duplicate_pad_numbers_are_jumpers no)
		(fp_rect
			(start -0.4318 0.9525)
			(end 0.4318 -0.9525)
			(stroke
				(width 0)
				(type default)
			)
			(fill no)
			(layer "F.CrtYd")
		)
		(fp_rect
			(start -0.4318 0.9525)
			(end 0.4318 -0.9525)
			(stroke
				(width 0)
				(type default)
			)
			(fill no)
			(layer "F.Fab")
		)
		(pad "1" smd custom
			(at 0 -0.4445 90)
			(size 0.1524 0.1524)
			(layers "F.Cu" "F.Mask" "F.Paste")
			(net "P12V_B")
			(options
				(clearance outline)
				(anchor circle)
			)
			(primitives
				(gr_poly
					(pts
						(arc
							(start 0.3048 -0.2032)
							(mid 0.275042 -0.275042)
							(end 0.2032 -0.3048)
						)
						(arc
							(start -0.2032 -0.3048)
							(mid -0.275042 -0.275042)
							(end -0.3048 -0.2032)
						)
						(arc
							(start -0.3048 0.2032)
							(mid -0.275042 0.275042)
							(end -0.2032 0.3048)
						)
						(arc
							(start 0.2032 0.3048)
							(mid 0.275042 0.275042)
							(end 0.3048 0.2032)
						)
					)
					(width 0)
					(fill yes)
				)
			)
		)
		(pad "2" smd custom
			(at 0 0.4445 90)
			(size 0.1524 0.1524)
			(layers "F.Cu" "F.Mask" "F.Paste")
			(net "SW_HDD_N14")
			(options
				(clearance outline)
				(anchor circle)
			)
			(primitives
				(gr_poly
					(pts
						(arc
							(start 0.3048 -0.2032)
							(mid 0.275042 -0.275042)
							(end 0.2032 -0.3048)
						)
						(arc
							(start -0.2032 -0.3048)
							(mid -0.275042 -0.275042)
							(end -0.3048 -0.2032)
						)
						(arc
							(start -0.3048 0.2032)
							(mid -0.275042 0.275042)
							(end -0.2032 0.3048)
						)
						(arc
							(start 0.2032 0.3048)
							(mid 0.275042 0.275042)
							(end 0.3048 0.2032)
						)
					)
					(width 0)
					(fill yes)
				)
			)
		)
	)
	(footprint ""
		(layer "F.Cu")
		(at 18.923 -150.622 90)
		(property "Reference" "R352"
			(at 0 0 90)
			(layer "F.SilkS")
			(hide yes)
			(effects
				(font
					(size 1.27 1.27)
				)
			)
		)
		(property "Value" "2R6F-GP"
			(at -0.0508 -4.8514 90)
			(unlocked yes)
			(layer "F.Fab")
			(hide yes)
			(effects
				(font
					(size 1.016 1.016)
					(thickness 0.1524)
				)
			)
		)
		(property "Device Type" "R1206H26"
			(at 0 -6.3754 90)
			(unlocked yes)
			(layer "F.Fab")
			(hide yes)
			(effects
				(font
					(size 1.016 1.016)
					(thickness 0.1524)
				)
			)
		)
		(duplicate_pad_numbers_are_jumpers no)
		(fp_line
			(start 1.016 -2.2352)
			(end 1.016 2.2352)
			(stroke
				(width 0.1524)
				(type default)
			)
			(layer "F.SilkS")
		)
		(fp_line
			(start -1.016 -2.2352)
			(end 1.016 -2.2352)
			(stroke
				(width 0.1524)
				(type default)
			)
			(layer "F.SilkS")
		)
		(fp_line
			(start 1.016 2.2352)
			(end -1.016 2.2352)
			(stroke
				(width 0.1524)
				(type default)
			)
			(layer "F.SilkS")
		)
		(fp_line
			(start -1.016 2.2352)
			(end -1.016 -2.2352)
			(stroke
				(width 0.1524)
				(type default)
			)
			(layer "F.SilkS")
		)
		(fp_rect
			(start -1.0922 2.3114)
			(end 1.0922 -2.3114)
			(stroke
				(width 0)
				(type default)
			)
			(fill no)
			(layer "F.CrtYd")
		)
		(fp_poly
			(pts
				(xy -1.0922 -2.3114) (xy 1.0922 -2.3114) (xy 1.0922 2.3114) (xy -1.0922 2.3114)
			)
			(stroke
				(width 0)
				(type default)
			)
			(fill no)
			(layer "F.Fab")
		)
		(pad "1" smd rect
			(at 0 -1.397 90)
			(size 1.651 1.27)
			(layers "F.Cu" "F.Mask" "F.Paste")
			(net "P12V_HDD12")
		)
		(pad "2" smd rect
			(at 0 1.397 90)
			(size 1.651 1.27)
			(layers "F.Cu" "F.Mask" "F.Paste")
			(net "12V_PRE_12")
		)
	)
	(footprint ""
		(layer "F.Cu")
		(at 473.8878 -10.6934 90)
		(property "Reference" "C494"
			(at 0 0 90)
			(layer "F.SilkS")
			(hide yes)
			(effects
				(font
					(size 1.27 1.27)
				)
			)
		)
		(property "Value" "SCD033U25V2KX-GP"
			(at 1.1811 -2.7051 90)
			(unlocked yes)
			(layer "F.Fab")
			(hide yes)
			(effects
				(font
					(size 1.016 1.016)
					(thickness 0.1524)
				)
			)
		)
		(property "Device Type" "C402H22"
			(at 1.1811 -4.2291 90)
			(unlocked yes)
			(layer "F.Fab")
			(hide yes)
			(effects
				(font
					(size 1.016 1.016)
					(thickness 0.1524)
				)
			)
		)
		(duplicate_pad_numbers_are_jumpers no)
		(fp_rect
			(start -0.4318 0.9525)
			(end 0.4318 -0.9525)
			(stroke
				(width 0)
				(type default)
			)
			(fill no)
			(layer "F.CrtYd")
		)
		(fp_rect
			(start -0.4318 0.9525)
			(end 0.4318 -0.9525)
			(stroke
				(width 0)
				(type default)
			)
			(fill no)
			(layer "F.Fab")
		)
		(pad "1" smd custom
			(at 0 -0.4445 90)
			(size 0.1524 0.1524)
			(layers "F.Cu" "F.Mask" "F.Paste")
			(net "P12V_B")
			(options
				(clearance outline)
				(anchor circle)
			)
			(primitives
				(gr_poly
					(pts
						(arc
							(start 0.3048 -0.2032)
							(mid 0.275042 -0.275042)
							(end 0.2032 -0.3048)
						)
						(arc
							(start -0.2032 -0.3048)
							(mid -0.275042 -0.275042)
							(end -0.3048 -0.2032)
						)
						(arc
							(start -0.3048 0.2032)
							(mid -0.275042 0.275042)
							(end -0.2032 0.3048)
						)
						(arc
							(start 0.2032 0.3048)
							(mid 0.275042 0.275042)
							(end 0.3048 0.2032)
						)
					)
					(width 0)
					(fill yes)
				)
			)
		)
		(pad "2" smd custom
			(at 0 0.4445 90)
			(size 0.1524 0.1524)
			(layers "F.Cu" "F.Mask" "F.Paste")
			(net "SW_HDD_N35")
			(options
				(clearance outline)
				(anchor circle)
			)
			(primitives
				(gr_poly
					(pts
						(arc
							(start 0.3048 -0.2032)
							(mid 0.275042 -0.275042)
							(end 0.2032 -0.3048)
						)
						(arc
							(start -0.2032 -0.3048)
							(mid -0.275042 -0.275042)
							(end -0.3048 -0.2032)
						)
						(arc
							(start -0.3048 0.2032)
							(mid -0.275042 0.275042)
							(end -0.2032 0.3048)
						)
						(arc
							(start 0.2032 0.3048)
							(mid 0.275042 0.275042)
							(end 0.3048 0.2032)
						)
					)
					(width 0)
					(fill yes)
				)
			)
		)
	)
	(footprint ""
		(layer "F.Cu")
		(at 87.376 -275.463 180)
		(property "Reference" "C62"
			(at 0 0 180)
			(layer "F.SilkS")
			(hide yes)
			(effects
				(font
					(size 1.27 1.27)
				)
			)
		)
		(property "Value" "SC1U25V3KX-GP"
			(at 0 -2.8194 180)
			(unlocked yes)
			(layer "F.Fab")
			(hide yes)
			(effects
				(font
					(size 1.016 1.016)
					(thickness 0.1524)
				)
			)
		)
		(property "Device Type" "C603H36"
			(at 0 -4.3434 180)
			(unlocked yes)
			(layer "F.Fab")
			(hide yes)
			(effects
				(font
					(size 1.016 1.016)
					(thickness 0.1524)
				)
			)
		)
		(duplicate_pad_numbers_are_jumpers no)
		(fp_line
			(start 0.508 0)
			(end -0.508 0)
			(stroke
				(width 0.2032)
				(type default)
			)
			(layer "F.SilkS")
		)
		(fp_rect
			(start -0.5842 1.3335)
			(end 0.5842 -1.3335)
			(stroke
				(width 0)
				(type default)
			)
			(fill no)
			(layer "F.CrtYd")
		)
		(fp_rect
			(start -0.5842 1.3335)
			(end 0.5842 -1.3335)
			(stroke
				(width 0)
				(type default)
			)
			(fill no)
			(layer "F.Fab")
		)
		(pad "1" smd custom
			(at 0 -0.762 180)
			(size 0.2159 0.2159)
			(layers "F.Cu" "F.Mask" "F.Paste")
			(net "P12V_HDD2")
			(options
				(clearance outline)
				(anchor circle)
			)
			(primitives
				(gr_poly
					(pts
						(arc
							(start -0.3302 -0.4318)
							(mid -0.402042 -0.402042)
							(end -0.4318 -0.3302)
						)
						(arc
							(start -0.4318 0.3302)
							(mid -0.402042 0.402042)
							(end -0.3302 0.4318)
						)
						(arc
							(start 0.3302 0.4318)
							(mid 0.402042 0.402042)
							(end 0.4318 0.3302)
						)
						(arc
							(start 0.4318 -0.3302)
							(mid 0.402042 -0.402042)
							(end 0.3302 -0.4318)
						)
					)
					(width 0)
					(fill yes)
				)
			)
		)
		(pad "2" smd custom
			(at 0 0.762 180)
			(size 0.2159 0.2159)
			(layers "F.Cu" "F.Mask" "F.Paste")
			(net "GND")
			(options
				(clearance outline)
				(anchor circle)
			)
			(primitives
				(gr_poly
					(pts
						(arc
							(start -0.3302 -0.4318)
							(mid -0.402042 -0.402042)
							(end -0.4318 -0.3302)
						)
						(arc
							(start -0.4318 0.3302)
							(mid -0.402042 0.402042)
							(end -0.3302 0.4318)
						)
						(arc
							(start 0.3302 0.4318)
							(mid 0.402042 0.402042)
							(end 0.4318 0.3302)
						)
						(arc
							(start 0.4318 -0.3302)
							(mid 0.402042 -0.402042)
							(end 0.3302 -0.4318)
						)
					)
					(width 0)
					(fill yes)
				)
			)
		)
	)
)
